(kicad_pcb
	(version 20240108)
	(generator "pcbnew")
	(generator_version "8.0")
	(general
		(thickness 1.62)
		(legacy_teardrops no)
	)
	(paper "A4")
	(title_block
		(title "Jetson Orin Baseboard")
		(date "2025-03-12")
		(rev "1.3.4")
		(company "Antmicro Ltd")
		(comment 1 "www.antmicro.com")
		(comment 9 "footprint 675 of 677 (U6), pads 1-70 of 78")
	)
	(layers
		(0 "F.Cu" signal)
		(1 "In1.Cu" signal)
		(2 "In2.Cu" signal)
		(3 "In3.Cu" signal)
		(4 "In4.Cu" jumper)
		(5 "In5.Cu" signal)
		(6 "In6.Cu" signal)
		(31 "B.Cu" signal)
		(32 "B.Adhes" user "B.Adhesive")
		(33 "F.Adhes" user "F.Adhesive")
		(34 "B.Paste" user)
		(35 "F.Paste" user)
		(36 "B.SilkS" user "B.Silkscreen")
		(37 "F.SilkS" user "F.Silkscreen")
		(38 "B.Mask" user)
		(39 "F.Mask" user)
		(40 "Dwgs.User" user "User.Drawings")
		(41 "Cmts.User" user "User.Comments")
		(42 "Eco1.User" user "User.Eco1")
		(43 "Eco2.User" user "User.Eco2")
		(44 "Edge.Cuts" user)
		(45 "Margin" user)
		(46 "B.CrtYd" user "B.Courtyard")
		(47 "F.CrtYd" user "F.Courtyard")
		(48 "B.Fab" user)
		(49 "F.Fab" user)
	)
	(footprint "antmicro-footprints:IC_TPS65987DDHRSHR"
		(layer "B.Cu")
		(at 66.3 103.1 90)
		(property "Reference" "U6"
			(at -1.8 4.7 -90)
			(layer "B.SilkS")
			(effects
				(font
					(size 0.7 0.7)
					(thickness 0.15)
				)
				(justify left bottom mirror)
			)
		)
		(property "Value" "TPS65988DHRSHR"
			(at 0 -4.9 -90)
			(layer "B.Fab")
			(effects
				(font
					(size 0.7 0.7)
					(thickness 0.15)
				)
				(justify left bottom mirror)
			)
		)
		(property "Footprint" "antmicro-footprints:IC_TPS65987DDHRSHR"
			(at 0 0 90)
			(layer "F.Fab")
			(hide yes)
			(effects
				(font
					(size 1.27 1.27)
					(thickness 0.15)
				)
			)
		)
		(property "Datasheet" "https://www.ti.com/lit/ds/symlink/tps65988.pdf?ts=1662726631004&ref_url=https%253A%252F%252Fwww.ti.com%252Fproduct%252FTPS65988"
			(at 0 0 90)
			(layer "F.Fab")
			(hide yes)
			(effects
				(font
					(size 1.27 1.27)
					(thickness 0.15)
				)
			)
		)
		(property "Author" "Antmicro"
			(at 169.4 36.8 0)
			(layer "B.Fab")
			(hide yes)
			(effects
				(font
					(size 1 1)
					(thickness 0.15)
				)
				(justify mirror)
			)
		)
		(property "License" "Apache-2.0"
			(at 169.4 36.8 0)
			(layer "B.Fab")
			(hide yes)
			(effects
				(font
					(size 1 1)
					(thickness 0.15)
				)
				(justify mirror)
			)
		)
		(property "MPN" "TPS65988DHRSHR "
			(at 169.4 36.8 0)
			(layer "B.Fab")
			(hide yes)
			(effects
				(font
					(size 1 1)
					(thickness 0.15)
				)
				(justify mirror)
			)
		)
		(property "Manufacturer" "Texas Instruments"
			(at 169.4 36.8 0)
			(layer "B.Fab")
			(hide yes)
			(effects
				(font
					(size 1 1)
					(thickness 0.15)
				)
				(justify mirror)
			)
		)
		(sheetname "USB Debug, DP")
		(sheetfile "usb.kicad_sch")
		(attr smd)
		(pad "1" smd roundrect
			(at -3.351 2.4 90)
			(size 0.8 0.65)
			(layers "B.Cu")
			(roundrect_rratio 0.09)
			(net 481 "USBPD2_HV")
			(pinfunction "PP_HV2")
			(pintype "bidirectional")
		)
		(pad "3" smd roundrect
			(at -3.351 1.601 90)
			(size 0.8 0.65)
			(layers "B.Cu")
			(roundrect_rratio 0.09)
			(net 261 "/USB Debug, DP/USBC0_VBUS")
			(pinfunction "VBUS2")
			(pintype "bidirectional")
		)
		(pad "5" smd roundrect
			(at -3.351 1 90)
			(size 0.7 0.2)
			(layers "B.Cu" "B.Paste" "B.Mask")
			(roundrect_rratio 0.25)
			(net 87 "+3V3")
			(pinfunction "VIN_3V3")
			(pintype "power_in")
		)
		(pad "6" smd roundrect
			(at -3.351 0.6 90)
			(size 0.7 0.2)
			(layers "B.Cu" "B.Paste" "B.Mask")
			(roundrect_rratio 0.25)
			(net 286 "/USB Debug, DP/PDC_ADCIN1")
			(pinfunction "ADCIN1")
			(pintype "input")
		)
		(pad "7" smd roundrect
			(at -3.351 0.202 90)
			(size 0.7 0.2)
			(layers "B.Cu" "B.Paste" "B.Mask")
			(roundrect_rratio 0.25)
			(net 404 "/USB Debug, DP/DRAIN1")
			(pinfunction "DRAIN2")
			(pintype "passive")
		)
		(pad "8" smd roundrect
			(at -3.351 -0.2 90)
			(size 0.7 0.2)
			(layers "B.Cu" "B.Paste" "B.Mask")
			(roundrect_rratio 0.25)
			(net 403 "/USB Debug, DP/DRAIN2")
			(pinfunction "DRAIN1")
			(pintype "passive")
		)
		(pad "9" smd roundrect
			(at -3.351 -0.598 90)
			(size 0.7 0.2)
			(layers "B.Cu" "B.Paste" "B.Mask")
			(roundrect_rratio 0.25)
			(net 134 "/USB Debug, DP/PDC_LDO_3V3")
			(pinfunction "LDO_3V3")
			(pintype "power_out")
		)
		(pad "10" smd roundrect
			(at -3.351 -0.998 90)
			(size 0.7 0.2)
			(layers "B.Cu" "B.Paste" "B.Mask")
			(roundrect_rratio 0.25)
			(net 287 "/USB Debug, DP/PDC_ADCIN2")
			(pinfunction "ADCIN2")
			(pintype "input")
		)
		(pad "11" smd roundrect
			(at -3.351 -1.6 90)
			(size 0.8 0.65)
			(layers "B.Cu")
			(roundrect_rratio 0.09)
			(net 480 "USBPD1_HV")
			(pinfunction "PP_HV1")
			(pintype "bidirectional")
		)
		(pad "13" smd roundrect
			(at -3.351 -2.398 90)
			(size 0.8 0.65)
			(layers "B.Cu")
			(roundrect_rratio 0.09)
			(net 196 "/USB Debug, DP/USBC3_VBUS")
			(pinfunction "VBUS1")
			(pintype "bidirectional")
		)
		(pad "15" smd roundrect
			(at -2.601 -3.35)
			(size 0.7 0.2)
			(layers "B.Cu" "B.Paste" "B.Mask")
			(roundrect_rratio 0.25)
			(net 403 "/USB Debug, DP/DRAIN2")
			(pinfunction "DRAIN1")
			(pintype "passive")
		)
		(pad "16" smd roundrect
			(at -2.202 -3.35)
			(size 0.7 0.2)
			(layers "B.Cu" "B.Paste" "B.Mask")
			(roundrect_rratio 0.25)
			(net 296 "/USB Debug, DP/PDC_FLIP")
			(pinfunction "GPIO0")
			(pintype "bidirectional")
		)
		(pad "17" smd roundrect
			(at -1.801 -3.35)
			(size 0.7 0.2)
			(layers "B.Cu" "B.Paste" "B.Mask")
			(roundrect_rratio 0.25)
			(net 298 "/USB Debug, DP/PDC_CTL0")
			(pinfunction "GPIO1")
			(pintype "bidirectional")
		)
		(pad "18" smd roundrect
			(at -1.401 -3.35)
			(size 0.7 0.2)
			(layers "B.Cu" "B.Paste" "B.Mask")
			(roundrect_rratio 0.25)
			(net 294 "/USB Debug, DP/PDC_CTL1")
			(pinfunction "GPIO2")
			(pintype "bidirectional")
		)
		(pad "19" smd roundrect
			(at -1 -3.35)
			(size 0.7 0.2)
			(layers "B.Cu" "B.Paste" "B.Mask")
			(roundrect_rratio 0.25)
			(net 403 "/USB Debug, DP/DRAIN2")
			(pinfunction "DRAIN1")
			(pintype "passive")
		)
		(pad "20" smd roundrect
			(at -0.6 -3.35)
			(size 0.7 0.2)
			(layers "B.Cu" "B.Paste" "B.Mask")
			(roundrect_rratio 0.25)
			(net 1 "GND")
			(pinfunction "GND")
			(pintype "power_in")
		)
		(pad "21" smd roundrect
			(at -0.202 -3.35)
			(size 0.7 0.2)
			(layers "B.Cu" "B.Paste" "B.Mask")
			(roundrect_rratio 0.25)
			(net 639 "/USB Debug, DP/PDC_I2C3_SCL")
			(pinfunction "I2C3_SCL/GPIO5")
			(pintype "bidirectional")
		)
		(pad "22" smd roundrect
			(at 0.2 -3.35)
			(size 0.7 0.2)
			(layers "B.Cu" "B.Paste" "B.Mask")
			(roundrect_rratio 0.25)
			(net 299 "/USB Debug, DP/PDC_I2C3_SDA")
			(pinfunction "I2C3_SDA/GPIO6")
			(pintype "bidirectional")
		)
		(pad "23" smd roundrect
			(at 0.598 -3.35)
			(size 0.7 0.2)
			(layers "B.Cu" "B.Paste" "B.Mask")
			(roundrect_rratio 0.25)
			(net 708 "/USB Debug, DP/~{PDC_I2C3_IRQ}")
			(pinfunction "~{I2C3_IRQ}/GPIO7")
			(pintype "bidirectional")
		)
		(pad "24" smd roundrect
			(at 0.998 -3.35)
			(size 0.7 0.2)
			(layers "B.Cu" "B.Paste" "B.Mask")
			(roundrect_rratio 0.25)
			(net 273 "/USB Debug, DP/USBC3_CC1")
			(pinfunction "C1_CC1")
			(pintype "bidirectional")
		)
		(pad "25" smd roundrect
			(at 1.398 -3.35)
			(size 0.7 0.2)
			(layers "B.Cu" "B.Paste" "B.Mask")
			(roundrect_rratio 0.25)
			(net 99 "+5V")
			(pinfunction "PP1_CABLE")
			(pintype "power_in")
		)
		(pad "26" smd roundrect
			(at 1.8 -3.35)
			(size 0.7 0.2)
			(layers "B.Cu" "B.Paste" "B.Mask")
			(roundrect_rratio 0.25)
			(net 276 "/USB Debug, DP/USBC3_CC2")
			(pinfunction "C1_CC2")
			(pintype "bidirectional")
		)
		(pad "27" smd roundrect
			(at 2.2 -3.35)
			(size 0.7 0.2)
			(layers "B.Cu" "B.Paste" "B.Mask")
			(roundrect_rratio 0.25)
			(net 302 "/USB Debug, DP/PDC_I2C1_SCL")
			(pinfunction "I2C1_SCL")
			(pintype "bidirectional")
		)
		(pad "28" smd roundrect
			(at 2.6 -3.35)
			(size 0.7 0.2)
			(layers "B.Cu" "B.Paste" "B.Mask")
			(roundrect_rratio 0.25)
			(net 303 "/USB Debug, DP/PDC_I2C1_SDA")
			(pinfunction "I2C1_SDA")
			(pintype "bidirectional")
		)
		(pad "29" smd roundrect
			(at 3.35 -2.6 90)
			(size 0.7 0.2)
			(layers "B.Cu" "B.Paste" "B.Mask")
			(roundrect_rratio 0.25)
			(net 713 "/USB Debug, DP/PDC_I2C1_IRQn")
			(pinfunction "~{I2C1_IRQ}")
			(pintype "output")
		)
		(pad "30" smd roundrect
			(at 3.35 -2.2 90)
			(size 0.7 0.2)
			(layers "B.Cu" "B.Paste" "B.Mask")
			(roundrect_rratio 0.25)
			(net 691 "Net-(U6A-GPIO3{slash}HPD1)")
			(pinfunction "GPIO3/HPD1")
			(pintype "bidirectional")
		)
		(pad "31" smd roundrect
			(at 3.35 -1.8 90)
			(size 0.7 0.2)
			(layers "B.Cu" "B.Paste" "B.Mask")
			(roundrect_rratio 0.25)
			(net 670 "/USB Debug, DP/PDC_HPD2")
			(pinfunction "GPIO4/HPD2")
			(pintype "bidirectional")
		)
		(pad "32" smd roundrect
			(at 3.35 -1.398 90)
			(size 0.7 0.2)
			(layers "B.Cu" "B.Paste" "B.Mask")
			(roundrect_rratio 0.25)
			(net 395 "/USB Debug, DP/PDC_I2C2_SCL")
			(pinfunction "I2C2_SCL")
			(pintype "bidirectional")
		)
		(pad "33" smd roundrect
			(at 3.35 -0.998 90)
			(size 0.7 0.2)
			(layers "B.Cu" "B.Paste" "B.Mask")
			(roundrect_rratio 0.25)
			(net 396 "/USB Debug, DP/PDC_I2C2_SDA")
			(pinfunction "I2C2_SDA")
			(pintype "bidirectional")
		)
		(pad "34" smd roundrect
			(at 3.35 -0.598 90)
			(size 0.7 0.2)
			(layers "B.Cu" "B.Paste" "B.Mask")
			(roundrect_rratio 0.25)
			(net 394 "/USB Debug, DP/PDC_I2C2_IRQn")
			(pinfunction "~{I2C2_IRQ}")
			(pintype "output")
		)
		(pad "35" smd roundrect
			(at 3.35 -0.2 90)
			(size 0.7 0.2)
			(layers "B.Cu" "B.Paste" "B.Mask")
			(roundrect_rratio 0.25)
			(net 133 "/USB Debug, DP/PDC_LDO_1V8")
			(pinfunction "LDO_1V8")
			(pintype "power_out")
		)
		(pad "36" smd roundrect
			(at 3.35 0.202 90)
			(size 0.7 0.2)
			(layers "B.Cu" "B.Paste" "B.Mask")
			(roundrect_rratio 0.25)
			(net 255 "PDC_MISO")
			(pinfunction "SPI_POCI/GPIO8")
			(pintype "bidirectional")
		)
		(pad "37" smd roundrect
			(at 3.35 0.6 90)
			(size 0.7 0.2)
			(layers "B.Cu" "B.Paste" "B.Mask")
			(roundrect_rratio 0.25)
			(net 256 "PDC_MOSI")
			(pinfunction "SPI_PICO/GPIO9")
			(pintype "bidirectional")
		)
		(pad "38" smd roundrect
			(at 3.35 1 90)
			(size 0.7 0.2)
			(layers "B.Cu" "B.Paste" "B.Mask")
			(roundrect_rratio 0.25)
			(net 254 "PDC_SCLK")
			(pinfunction "SPI_CLK/GPIO10")
			(pintype "bidirectional")
		)
		(pad "39" smd roundrect
			(at 3.35 1.401 90)
			(size 0.7 0.2)
			(layers "B.Cu" "B.Paste" "B.Mask")
			(roundrect_rratio 0.25)
			(net 253 "~{PDC_CS}")
			(pinfunction "~{SPI_CS}/GPIO11")
			(pintype "bidirectional")
		)
		(pad "40" smd roundrect
			(at 3.35 1.801 90)
			(size 0.7 0.2)
			(layers "B.Cu" "B.Paste" "B.Mask")
			(roundrect_rratio 0.25)
			(net 693 "unconnected-(U6A-GPIO12-Pad40)")
			(pinfunction "GPIO12")
			(pintype "bidirectional+no_connect")
		)
		(pad "41" smd roundrect
			(at 3.35 2.202 90)
			(size 0.7 0.2)
			(layers "B.Cu" "B.Paste" "B.Mask")
			(roundrect_rratio 0.25)
			(net 694 "unconnected-(U6A-GPIO13-Pad41)")
			(pinfunction "GPIO13")
			(pintype "bidirectional+no_connect")
		)
		(pad "42" smd roundrect
			(at 3.35 2.601 90)
			(size 0.7 0.2)
			(layers "B.Cu" "B.Paste" "B.Mask")
			(roundrect_rratio 0.25)
			(net 300 "/USB Debug, DP/PDC_GPIO14")
			(pinfunction "GPIO14/PWM1")
			(pintype "bidirectional")
		)
		(pad "43" smd roundrect
			(at 2.6 3.351)
			(size 0.7 0.2)
			(layers "B.Cu" "B.Paste" "B.Mask")
			(roundrect_rratio 0.25)
			(net 301 "/USB Debug, DP/PDC_GPIO15")
			(pinfunction "GPIO15/PWM2")
			(pintype "bidirectional")
		)
		(pad "44" smd roundrect
			(at 2.2 3.351)
			(size 0.7 0.2)
			(layers "B.Cu" "B.Paste" "B.Mask")
			(roundrect_rratio 0.25)
			(net 285 "/USB Debug, DP/PDC_RESET")
			(pinfunction "HRESET")
			(pintype "input")
		)
		(pad "45" smd roundrect
			(at 1.8 3.351)
			(size 0.7 0.2)
			(layers "B.Cu" "B.Paste" "B.Mask")
			(roundrect_rratio 0.25)
			(net 277 "/USB Debug, DP/USBC0_CC1")
			(pinfunction "C2_CC1")
			(pintype "bidirectional")
		)
		(pad "46" smd roundrect
			(at 1.398 3.351)
			(size 0.7 0.2)
			(layers "B.Cu" "B.Paste" "B.Mask")
			(roundrect_rratio 0.25)
			(net 99 "+5V")
			(pinfunction "PP2_CABLE")
			(pintype "power_in")
		)
		(pad "47" smd roundrect
			(at 0.998 3.351)
			(size 0.7 0.2)
			(layers "B.Cu" "B.Paste" "B.Mask")
			(roundrect_rratio 0.25)
			(net 278 "/USB Debug, DP/USBC0_CC2")
			(pinfunction "C2_CC2")
			(pintype "bidirectional")
		)
		(pad "48" smd roundrect
			(at 0.598 3.351)
			(size 0.7 0.2)
			(layers "B.Cu" "B.Paste" "B.Mask")
			(roundrect_rratio 0.25)
			(net 549 "/USB Debug, DP/USBC3_5V_PEN")
			(pinfunction "GPIO16/PP_EXT1")
			(pintype "bidirectional")
		)
		(pad "49" smd roundrect
			(at 0.2 3.351)
			(size 0.7 0.2)
			(layers "B.Cu" "B.Paste" "B.Mask")
			(roundrect_rratio 0.25)
			(net 553 "/USB Debug, DP/USBC0_5V_PEN")
			(pinfunction "GPIO17/PP_EXT2")
			(pintype "bidirectional")
		)
		(pad "50" smd roundrect
			(at -0.202 3.351)
			(size 0.7 0.2)
			(layers "B.Cu" "B.Paste" "B.Mask")
			(roundrect_rratio 0.25)
			(net 695 "unconnected-(U6B-C1_USB_P{slash}GPIO18-Pad50)")
			(pinfunction "C1_USB_P/GPIO18")
			(pintype "bidirectional+no_connect")
		)
		(pad "51" smd roundrect
			(at -0.6 3.351)
			(size 0.7 0.2)
			(layers "B.Cu" "B.Paste" "B.Mask")
			(roundrect_rratio 0.25)
			(net 1 "GND")
			(pinfunction "GND")
			(pintype "passive")
		)
		(pad "52" smd roundrect
			(at -1 3.351)
			(size 0.7 0.2)
			(layers "B.Cu" "B.Paste" "B.Mask")
			(roundrect_rratio 0.25)
			(net 404 "/USB Debug, DP/DRAIN1")
			(pinfunction "DRAIN2")
			(pintype "passive")
		)
		(pad "53" smd roundrect
			(at -1.401 3.351)
			(size 0.7 0.2)
			(layers "B.Cu" "B.Paste" "B.Mask")
			(roundrect_rratio 0.25)
			(net 696 "unconnected-(U6B-C1_USB_N{slash}GPIO19-Pad53)")
			(pinfunction "C1_USB_N/GPIO19")
			(pintype "bidirectional+no_connect")
		)
		(pad "54" smd roundrect
			(at -1.801 3.351)
			(size 0.7 0.2)
			(layers "B.Cu" "B.Paste" "B.Mask")
			(roundrect_rratio 0.25)
			(net 697 "unconnected-(U6C-C2_USB_P{slash}GPIO20-Pad54)")
			(pinfunction "C2_USB_P/GPIO20")
			(pintype "bidirectional+no_connect")
		)
		(pad "55" smd roundrect
			(at -2.202 3.351)
			(size 0.7 0.2)
			(layers "B.Cu" "B.Paste" "B.Mask")
			(roundrect_rratio 0.25)
			(net 698 "unconnected-(U6C-C2_USB_N{slash}GPIO21-Pad55)")
			(pinfunction "C2_USB_N/GPIO21")
			(pintype "bidirectional+no_connect")
		)
		(pad "56" smd roundrect
			(at -2.601 3.351)
			(size 0.7 0.2)
			(layers "B.Cu" "B.Paste" "B.Mask")
			(roundrect_rratio 0.25)
			(net 404 "/USB Debug, DP/DRAIN1")
			(pinfunction "DRAIN2")
			(pintype "passive")
		)
		(pad "57" thru_hole circle
			(at -2.351 0.576 90)
			(size 0.45 0.45)
			(drill 0.1)
			(layers "*.Cu")
			(remove_unused_layers no)
			(net 404 "/USB Debug, DP/DRAIN1")
			(pinfunction "DRAIN2")
			(pintype "passive")
		)
		(pad "57" thru_hole circle
			(at -2.351 1.45 90)
			(size 0.45 0.45)
			(drill 0.1)
			(layers "*.Cu")
			(remove_unused_layers no)
			(net 404 "/USB Debug, DP/DRAIN1")
			(pinfunction "DRAIN2")
			(pintype "passive")
		)
		(pad "57" thru_hole circle
			(at -2.351 2.327 90)
			(size 0.45 0.45)
			(drill 0.1)
			(layers "*.Cu")
			(remove_unused_layers no)
			(net 404 "/USB Debug, DP/DRAIN1")
			(pinfunction "DRAIN2")
			(pintype "passive")
		)
		(pad "57" smd roundrect
			(at -1.875 1.45)
			(size 2.6 1.75)
			(layers "B.Cu" "B.Mask")
			(roundrect_rratio 0.05714285714)
			(net 404 "/USB Debug, DP/DRAIN1")
			(pinfunction "DRAIN2")
			(pintype "passive")
			(solder_mask_margin 0.05)
		)
		(pad "57" thru_hole circle
			(at -1.401 0.577 90)
			(size 0.45 0.45)
			(drill 0.1)
			(layers "*.Cu")
			(remove_unused_layers no)
			(net 404 "/USB Debug, DP/DRAIN1")
			(pinfunction "DRAIN2")
			(pintype "passive")
		)
		(pad "57" thru_hole circle
			(at -1.401 1.45 90)
			(size 0.45 0.45)
			(drill 0.1)
			(layers "*.Cu")
			(remove_unused_layers no)
			(net 404 "/USB Debug, DP/DRAIN1")
			(pinfunction "DRAIN2")
			(pintype "passive")
		)
		(pad "57" thru_hole circle
			(at -1.401 2.327 90)
			(size 0.45 0.45)
			(drill 0.1)
			(layers "*.Cu")
			(remove_unused_layers no)
			(net 404 "/USB Debug, DP/DRAIN1")
			(pinfunction "DRAIN2")
			(pintype "passive")
		)
		(pad "58" thru_hole circle
			(at -2.351 -2.35 90)
			(size 0.45 0.45)
			(drill 0.1)
			(layers "*.Cu")
			(remove_unused_layers no)
			(net 403 "/USB Debug, DP/DRAIN2")
			(pinfunction "DRAIN1")
			(pintype "passive")
		)
		(pad "58" thru_hole circle
			(at -2.351 -1.475 90)
			(size 0.45 0.45)
			(drill 0.1)
			(layers "*.Cu")
			(remove_unused_layers no)
			(net 403 "/USB Debug, DP/DRAIN2")
			(pinfunction "DRAIN1")
			(pintype "passive")
		)
		(pad "58" thru_hole circle
			(at -2.351 -0.598 90)
			(size 0.45 0.45)
			(drill 0.1)
			(layers "*.Cu")
			(remove_unused_layers no)
			(net 403 "/USB Debug, DP/DRAIN2")
			(pinfunction "DRAIN1")
			(pintype "passive")
		)
		(pad "58" smd roundrect
			(at -1.875 -1.475)
			(size 2.55 1.75)
			(layers "B.Cu" "B.Mask")
			(roundrect_rratio 0.05714285714)
			(net 403 "/USB Debug, DP/DRAIN2")
			(pinfunction "DRAIN1")
			(pintype "passive")
			(solder_mask_margin 0.05)
		)
		(pad "58" thru_hole circle
			(at -1.401 -2.349 90)
			(size 0.45 0.45)
			(drill 0.1)
			(layers "*.Cu")
			(remove_unused_layers no)
			(net 403 "/USB Debug, DP/DRAIN2")
			(pinfunction "DRAIN1")
			(pintype "passive")
		)
		(pad "58" thru_hole circle
			(at -1.401 -1.475 90)
			(size 0.45 0.45)
			(drill 0.1)
			(layers "*.Cu")
			(remove_unused_layers no)
			(net 403 "/USB Debug, DP/DRAIN2")
			(pinfunction "DRAIN1")
			(pintype "passive")
		)
		(pad "58" thru_hole circle
			(at -1.401 -0.598 90)
			(size 0.45 0.45)
			(drill 0.1)
			(layers "*.Cu")
			(remove_unused_layers no)
			(net 403 "/USB Debug, DP/DRAIN2")
			(pinfunction "DRAIN1")
			(pintype "passive")
		)
		(pad "59" thru_hole circle
			(at -0.152 -1.322 90)
			(size 0.45 0.45)
			(drill 0.1)
			(layers "*.Cu")
			(remove_unused_layers no)
			(net 1 "GND")
			(pinfunction "GND_EP")
			(pintype "power_in")
		)
		(pad "59" thru_hole circle
			(at -0.15 0 90)
			(size 0.45 0.45)
			(drill 0.1)
			(layers "*.Cu")
			(remove_unused_layers no)
			(net 1 "GND")
			(pinfunction "GND_EP")
			(pintype "power_in")
		)
		(pad "59" thru_hole circle
			(at -0.15 1.321 90)
			(size 0.45 0.45)
			(drill 0.1)
			(layers "*.Cu")
			(remove_unused_layers no)
			(net 1 "GND")
			(pinfunction "GND_EP")
			(pintype "power_in")
		)
		(pad "59" thru_hole circle
			(at 1.048 -2.496 90)
			(size 0.45 0.45)
			(drill 0.1)
			(layers "*.Cu")
			(remove_unused_layers no)
			(net 1 "GND")
			(pinfunction "GND_EP")
			(pintype "power_in")
		)
	)
)
